# BASEBOARD_FAB2 (Tioga Pass) — schematic netlist excerpt (pin names and nets, part order shuffled) for the footprints in the layout excerpt that follows; sources: Cadence DE-HDL packaged netlist, KiCad conversion of Wiwynn_Tioga_Pass_MB.brd

R8D14  RES  4.75K 1% CHIP  pkg 0402  page 133 : A = P3V3_STBY ; B = FP_PWR_ID_LED_N
R25W151  RES  4.75K 1% CHIP  pkg 0402  page 150 : A = GND ; B = RMII_BMC_PCH_SPRNGVLLE_TXD1_R
R3P3  RES  0.0 5% CHIP  pkg 0402  page 121 : A = RMII_SPRNGVLLE_BMC_PCH_RXD0 ; B = RMII_SPRNGVLLE_BMC_PCH_RXD0_R1

(kicad_pcb
	(version 20260206)
	(generator "pcbnew")
	(generator_version "10.0")
	(general
		(thickness 1.6)
		(legacy_teardrops no)
	)
	(paper "A4")
	(title_block
		(title "Wiwynn_Tioga_Pass_MB.brd")
		(comment 1 "Tioga Pass / footprints 1136-1138 of 4770")
	)
	(layers
		(0 "F.Cu" signal "TOP")
		(4 "In1.Cu" signal "L2GND")
		(6 "In2.Cu" signal "L3")
		(8 "In3.Cu" signal "L4GND")
		(10 "In4.Cu" signal "L5")
		(12 "In5.Cu" signal "L6GND")
		(14 "In6.Cu" signal "L7VCC")
		(16 "In7.Cu" signal "L8VCC")
		(18 "In8.Cu" signal "L9GND")
		(20 "In9.Cu" signal "L10")
		(22 "In10.Cu" signal "L11GND")
		(24 "In11.Cu" signal "L12")
		(26 "In12.Cu" signal "L13GND")
		(2 "B.Cu" signal "BOTTOM")
		(9 "F.Adhes" user "F.Adhesive")
		(11 "B.Adhes" user "B.Adhesive")
		(13 "F.Paste" user "Package Geometry/Pastemask Top")
		(15 "B.Paste" user "Package Geometry/Pastemask Bottom")
		(5 "F.SilkS" user "Ref Des/Silkscreen Top")
		(7 "B.SilkS" user "Ref Des/Silkscreen Bottom")
		(1 "F.Mask" user "Board Geometry/Soldermask Top")
		(3 "B.Mask" user "Board Geometry/Soldermask Bottom")
		(17 "Dwgs.User" user "User.Drawings")
		(19 "Cmts.User" user "User.Comments")
		(21 "Eco1.User" user "User.Eco1")
		(23 "Eco2.User" user "User.Eco2")
		(25 "Edge.Cuts" user "Board Geometry/Outline")
		(27 "Margin" user)
		(31 "F.CrtYd" user "Package Geometry/Place Bound Top")
		(29 "B.CrtYd" user "Package Geometry/Place Bound Bottom")
		(35 "F.Fab" user "Ref Des/Assembly Top")
		(33 "B.Fab" user "Ref Des/Assembly Bottom")
	)
	(footprint ""
		(layer "F.Cu")
		(at 393.827 -87.3125 180)
		(property "Reference" "R8D14"
			(at 0 0 180)
			(layer "F.SilkS")
			(hide yes)
			(effects
				(font
					(size 1.27 1.27)
				)
			)
		)
		(property "Value" ""
			(at 0 0 180)
			(layer "F.Fab")
			(effects
				(font
					(size 1.27 1.27)
				)
			)
		)
		(duplicate_pad_numbers_are_jumpers no)
		(fp_poly
			(pts
				(xy -0.2794 -0.1016) (xy 0.2794 -0.1016) (xy 0.2794 0.9906) (xy -0.2794 0.9906)
			)
			(stroke
				(width 0)
				(type default)
			)
			(fill no)
			(layer "F.CrtYd")
		)
		(fp_line
			(start 0.2794 0.9906)
			(end 0.2794 -0.1016)
			(stroke
				(width 0.1)
				(type default)
			)
			(layer "F.Fab")
		)
		(fp_line
			(start 0.2794 -0.1016)
			(end -0.2794 -0.1016)
			(stroke
				(width 0.1)
				(type default)
			)
			(layer "F.Fab")
		)
		(fp_line
			(start -0.2794 0.9906)
			(end 0.2794 0.9906)
			(stroke
				(width 0.1)
				(type default)
			)
			(layer "F.Fab")
		)
		(fp_line
			(start -0.2794 -0.1016)
			(end -0.2794 0.9906)
			(stroke
				(width 0.1)
				(type default)
			)
			(layer "F.Fab")
		)
		(pad "1" smd rect
			(at 0 0 180)
			(size 0.508 0.508)
			(layers "F.Cu" "F.Mask" "F.Paste")
			(net "P3V3_STBY")
		)
		(pad "2" smd rect
			(at 0 0.889 180)
			(size 0.508 0.508)
			(layers "F.Cu" "F.Mask" "F.Paste")
			(net "FP_PWR_ID_LED_N")
		)
		(zone
			(layer "F.Cu")
			(hatch none 0.5)
			(connect_pads
				(clearance 0)
			)
			(min_thickness 0.25)
			(keepout
				(tracks not_allowed)
				(vias allowed)
				(pads allowed)
				(copperpour not_allowed)
				(footprints allowed)
			)
			(placement
				(enabled no)
				(sheetname "")
			)
			(fill
				(thermal_gap 0.5)
				(thermal_bridge_width 0.5)
				(island_removal_mode 0)
			)
			(polygon
				(pts
					(xy 394.081 -87.9475) (xy 393.573 -87.9475) (xy 393.573 -87.5665) (xy 394.081 -87.5665)
				)
			)
		)
		(zone
			(layer "F.Cu")
			(hatch none 0.5)
			(connect_pads
				(clearance 0)
			)
			(min_thickness 0.25)
			(keepout
				(tracks allowed)
				(vias not_allowed)
				(pads allowed)
				(copperpour not_allowed)
				(footprints allowed)
			)
			(placement
				(enabled no)
				(sheetname "")
			)
			(fill
				(thermal_gap 0.5)
				(thermal_bridge_width 0.5)
				(island_removal_mode 0)
			)
			(polygon
				(pts
					(xy 394.081 -87.5665) (xy 393.573 -87.5665) (xy 393.573 -87.9475) (xy 394.081 -87.9475)
				)
			)
		)
	)
	(footprint ""
		(layer "F.Cu")
		(at 388.366 -87.3125 180)
		(property "Reference" "R3P3"
			(at 0 0 180)
			(layer "F.SilkS")
			(hide yes)
			(effects
				(font
					(size 1.27 1.27)
				)
			)
		)
		(property "Value" ""
			(at 0 0 180)
			(layer "F.Fab")
			(effects
				(font
					(size 1.27 1.27)
				)
			)
		)
		(duplicate_pad_numbers_are_jumpers no)
		(fp_poly
			(pts
				(xy -0.2794 -0.1016) (xy 0.2794 -0.1016) (xy 0.2794 0.9906) (xy -0.2794 0.9906)
			)
			(stroke
				(width 0)
				(type default)
			)
			(fill no)
			(layer "F.CrtYd")
		)
		(fp_line
			(start 0.2794 0.9906)
			(end 0.2794 -0.1016)
			(stroke
				(width 0.1)
				(type default)
			)
			(layer "F.Fab")
		)
		(fp_line
			(start 0.2794 -0.1016)
			(end -0.2794 -0.1016)
			(stroke
				(width 0.1)
				(type default)
			)
			(layer "F.Fab")
		)
		(fp_line
			(start -0.2794 0.9906)
			(end 0.2794 0.9906)
			(stroke
				(width 0.1)
				(type default)
			)
			(layer "F.Fab")
		)
		(fp_line
			(start -0.2794 -0.1016)
			(end -0.2794 0.9906)
			(stroke
				(width 0.1)
				(type default)
			)
			(layer "F.Fab")
		)
		(pad "1" smd rect
			(at 0 0 180)
			(size 0.508 0.508)
			(layers "F.Cu" "F.Mask" "F.Paste")
			(net "RMII_SPRNGVLLE_BMC_PCH_RXD0")
		)
		(pad "2" smd rect
			(at 0 0.889 180)
			(size 0.508 0.508)
			(layers "F.Cu" "F.Mask" "F.Paste")
			(net "RMII_SPRNGVLLE_BMC_PCH_RXD0_R1")
		)
		(zone
			(layer "F.Cu")
			(hatch none 0.5)
			(connect_pads
				(clearance 0)
			)
			(min_thickness 0.25)
			(keepout
				(tracks not_allowed)
				(vias allowed)
				(pads allowed)
				(copperpour not_allowed)
				(footprints allowed)
			)
			(placement
				(enabled no)
				(sheetname "")
			)
			(fill
				(thermal_gap 0.5)
				(thermal_bridge_width 0.5)
				(island_removal_mode 0)
			)
			(polygon
				(pts
					(xy 388.62 -87.9475) (xy 388.112 -87.9475) (xy 388.112 -87.5665) (xy 388.62 -87.5665)
				)
			)
		)
		(zone
			(layer "F.Cu")
			(hatch none 0.5)
			(connect_pads
				(clearance 0)
			)
			(min_thickness 0.25)
			(keepout
				(tracks allowed)
				(vias not_allowed)
				(pads allowed)
				(copperpour not_allowed)
				(footprints allowed)
			)
			(placement
				(enabled no)
				(sheetname "")
			)
			(fill
				(thermal_gap 0.5)
				(thermal_bridge_width 0.5)
				(island_removal_mode 0)
			)
			(polygon
				(pts
					(xy 388.62 -87.5665) (xy 388.112 -87.5665) (xy 388.112 -87.9475) (xy 388.62 -87.9475)
				)
			)
		)
	)
	(footprint ""
		(layer "F.Cu")
		(at 401.955 -24.892)
		(property "Reference" "R25W151"
			(at -0.8382 -0.67818 0)
			(unlocked yes)
			(layer "F.SilkS")
			(effects
				(font
					(size 0.4064 0.254)
					(thickness 0.1524)
				)
				(justify left)
			)
		)
		(property "Value" ""
			(at 0 0 0)
			(layer "F.Fab")
			(effects
				(font
					(size 1.27 1.27)
				)
			)
		)
		(duplicate_pad_numbers_are_jumpers no)
		(fp_poly
			(pts
				(xy -0.2794 -0.1016) (xy 0.2794 -0.1016) (xy 0.2794 0.9906) (xy -0.2794 0.9906)
			)
			(stroke
				(width 0)
				(type default)
			)
			(fill no)
			(layer "F.CrtYd")
		)
		(fp_line
			(start -0.2794 -0.1016)
			(end -0.2794 0.9906)
			(stroke
				(width 0.1)
				(type default)
			)
			(layer "F.Fab")
		)
		(fp_line
			(start -0.2794 0.9906)
			(end 0.2794 0.9906)
			(stroke
				(width 0.1)
				(type default)
			)
			(layer "F.Fab")
		)
		(fp_line
			(start 0.2794 -0.1016)
			(end -0.2794 -0.1016)
			(stroke
				(width 0.1)
				(type default)
			)
			(layer "F.Fab")
		)
		(fp_line
			(start 0.2794 0.9906)
			(end 0.2794 -0.1016)
			(stroke
				(width 0.1)
				(type default)
			)
			(layer "F.Fab")
		)
		(pad "1" smd rect
			(at 0 0)
			(size 0.508 0.508)
			(layers "F.Cu" "F.Mask" "F.Paste")
			(net "GND")
		)
		(pad "2" smd rect
			(at 0 0.889)
			(size 0.508 0.508)
			(layers "F.Cu" "F.Mask" "F.Paste")
			(net "RMII_BMC_PCH_SPRNGVLLE_TXD1_R")
		)
		(zone
			(layer "F.Cu")
			(hatch none 0.5)
			(connect_pads
				(clearance 0)
			)
			(min_thickness 0.25)
			(keepout
				(tracks allowed)
				(vias not_allowed)
				(pads allowed)
				(copperpour not_allowed)
				(footprints allowed)
			)
			(placement
				(enabled no)
				(sheetname "")
			)
			(fill
				(thermal_gap 0.5)
				(thermal_bridge_width 0.5)
				(island_removal_mode 0)
			)
			(polygon
				(pts
					(xy 401.701 -24.638) (xy 402.209 -24.638) (xy 402.209 -24.257) (xy 401.701 -24.257)
				)
			)
		)
		(zone
			(layer "F.Cu")
			(hatch none 0.5)
			(connect_pads
				(clearance 0)
			)
			(min_thickness 0.25)
			(keepout
				(tracks not_allowed)
				(vias allowed)
				(pads allowed)
				(copperpour not_allowed)
				(footprints allowed)
			)
			(placement
				(enabled no)
				(sheetname "")
			)
			(fill
				(thermal_gap 0.5)
				(thermal_bridge_width 0.5)
				(island_removal_mode 0)
			)
			(polygon
				(pts
					(xy 401.701 -24.257) (xy 402.209 -24.257) (xy 402.209 -24.638) (xy 401.701 -24.638)
				)
			)
		)
	)
)
